(kicad_pcb
	(version 20260206)
	(generator "pcbnew")
	(generator_version "10.0")
	(general
		(thickness 1.6)
		(legacy_teardrops no)
	)
	(paper "A4")
	(title_block
		(title "12092022_DA0F0TMDCD0_F0T_Management_Board_D_brd_V3_OCP.brd")
		(comment 1 "Grand Teton / footprint 124 of 1440 (U5), pads 333-446 of 624")
	)
	(layers
		(0 "F.Cu" signal "TOP")
		(4 "In1.Cu" signal "GND")
		(6 "In2.Cu" signal "IN1")
		(8 "In3.Cu" signal "GND1")
		(10 "In4.Cu" signal "IN2")
		(12 "In5.Cu" signal "VCC")
		(14 "In6.Cu" signal "VCC1")
		(16 "In7.Cu" signal "IN3")
		(18 "In8.Cu" signal "GND2")
		(20 "In9.Cu" signal "IN4")
		(22 "In10.Cu" signal "GND3")
		(2 "B.Cu" signal "BOTTOM")
		(9 "F.Adhes" user "F.Adhesive")
		(11 "B.Adhes" user "B.Adhesive")
		(13 "F.Paste" user "Package Geometry/Pastemask Top")
		(15 "B.Paste" user "Package Geometry/Pastemask Bottom")
		(5 "F.SilkS" user "Ref Des/Silkscreen Top")
		(7 "B.SilkS" user "Ref Des/Silkscreen Bottom")
		(1 "F.Mask" user "Board Geometry/Soldermask Top")
		(3 "B.Mask" user "Board Geometry/Soldermask Bottom")
		(17 "Dwgs.User" user "User.Drawings")
		(19 "Cmts.User" user "User.Comments")
		(21 "Eco1.User" user "User.Eco1")
		(23 "Eco2.User" user "User.Eco2")
		(25 "Edge.Cuts" user "Board Geometry/Outline")
		(27 "Margin" user)
		(31 "F.CrtYd" user "Package Geometry/Place Bound Top")
		(29 "B.CrtYd" user "Package Geometry/Place Bound Bottom")
		(35 "F.Fab" user "Ref Des/Assembly Top")
		(33 "B.Fab" user "Ref Des/Assembly Bottom")
	)
	(footprint ""
		(layer "F.Cu")
		(at 54.894988 -49.37125 180)
		(property "Reference" "U5"
			(at -11.094212 -12.07262 0)
			(unlocked yes)
			(layer "F.SilkS")
			(effects
				(font
					(size 0.7874 0.5842)
					(thickness 0.1524)
				)
				(justify left)
			)
		)
		(property "Value" ""
			(at 0 0 180)
			(layer "F.Fab")
			(effects
				(font
					(size 1.27 1.27)
				)
			)
		)
		(duplicate_pad_numbers_are_jumpers no)
		(pad "H10" smd circle
			(at -2.800096 -4.400042 180)
			(size 0.4064 0.4064)
			(layers "F.Cu" "F.Mask" "F.Paste")
			(net "GND")
		)
		(pad "H11" smd circle
			(at -1.999996 -4.400042 180)
			(size 0.4064 0.4064)
			(layers "F.Cu" "F.Mask" "F.Paste")
			(net "GND")
		)
		(pad "H12" smd circle
			(at -1.199896 -4.400042 180)
			(size 0.4064 0.4064)
			(layers "F.Cu" "F.Mask" "F.Paste")
			(net "P1V8_AUX")
		)
		(pad "H13" smd circle
			(at -0.40005 -4.400042 180)
			(size 0.4064 0.4064)
			(layers "F.Cu" "F.Mask" "F.Paste")
			(net "GND")
		)
		(pad "H14" smd circle
			(at 0.40005 -4.400042 180)
			(size 0.4064 0.4064)
			(layers "F.Cu" "F.Mask" "F.Paste")
			(net "P3V3_STBY_PLLAHVDD")
		)
		(pad "H15" smd circle
			(at 1.199896 -4.400042 180)
			(size 0.4064 0.4064)
			(layers "F.Cu" "F.Mask" "F.Paste")
			(net "P3V3_AUX")
		)
		(pad "H16" smd circle
			(at 1.999996 -4.400042 180)
			(size 0.4064 0.4064)
			(layers "F.Cu" "F.Mask" "F.Paste")
			(net "P3V3_AUX")
		)
		(pad "H17" smd circle
			(at 2.800096 -4.400042 180)
			(size 0.4064 0.4064)
			(layers "F.Cu" "F.Mask" "F.Paste")
			(net "P3V3_AUX")
		)
		(pad "H18" smd circle
			(at 3.599942 -4.400042 180)
			(size 0.4064 0.4064)
			(layers "F.Cu" "F.Mask" "F.Paste")
			(net "P3V3_P1V8_SD2VDD")
		)
		(pad "H19" smd circle
			(at 4.400042 -4.400042 180)
			(size 0.4064 0.4064)
			(layers "F.Cu" "F.Mask" "F.Paste")
			(net "P3V3_P1V8_SD2VDD")
		)
		(pad "H21" smd circle
			(at 5.999988 -4.400042 180)
			(size 0.4064 0.4064)
			(layers "F.Cu" "F.Mask" "F.Paste")
			(net "P3V3_P1V8_SD1VDD")
		)
		(pad "H22" smd circle
			(at 6.800088 -4.400042 180)
			(size 0.4064 0.4064)
			(layers "F.Cu" "F.Mask" "F.Paste")
			(net "FM_BMC_CPU_FBRK_OUT_N")
		)
		(pad "H23" smd circle
			(at 7.599934 -4.400042 180)
			(size 0.4064 0.4064)
			(layers "F.Cu" "F.Mask" "F.Paste")
			(net "RST_SGPIO_RESET_BMC_N")
		)
		(pad "H24" smd circle
			(at 8.400034 -4.400042 180)
			(size 0.4064 0.4064)
			(layers "F.Cu" "F.Mask" "F.Paste")
			(net "RST_PLTRST_R_N")
		)
		(pad "H25" smd circle
			(at 9.19988 -4.400042 180)
			(size 0.4064 0.4064)
			(layers "F.Cu" "F.Mask" "F.Paste")
			(net "FM_ESPI_PLD_R1_EN")
		)
		(pad "H26" smd circle
			(at 9.99998 -4.400042 180)
			(size 0.4064 0.4064)
			(layers "F.Cu" "F.Mask" "F.Paste")
			(net "SMB_BMC_ALERT3_R_N")
		)
		(pad "J1" smd circle
			(at -9.99998 -3.599942 180)
			(size 0.4064 0.4064)
			(layers "F.Cu" "F.Mask" "F.Paste")
			(net "M_BMC_DDR4_MODT")
		)
		(pad "J2" smd circle
			(at -9.19988 -3.599942 180)
			(size 0.4064 0.4064)
			(layers "F.Cu" "F.Mask" "F.Paste")
			(net "GND")
		)
		(pad "J3" smd circle
			(at -8.400034 -3.599942 180)
			(size 0.4064 0.4064)
			(layers "F.Cu" "F.Mask" "F.Paste")
			(net "M_BMC_DDR4_MA<4>")
		)
		(pad "J4" smd circle
			(at -7.599934 -3.599942 180)
			(size 0.4064 0.4064)
			(layers "F.Cu" "F.Mask" "F.Paste")
			(net "M_BMC_DDR4_MCAS_N")
		)
		(pad "J5" smd circle
			(at -6.800088 -3.599942 180)
			(size 0.4064 0.4064)
			(layers "F.Cu" "F.Mask" "F.Paste")
			(net "M_BMC_DDR4_MRAS_N")
		)
		(pad "J6" smd circle
			(at -5.999988 -3.599942 180)
			(size 0.4064 0.4064)
			(layers "F.Cu" "F.Mask" "F.Paste")
			(net "P1V2_AUX")
		)
		(pad "J8" smd circle
			(at -4.400042 -3.599942 180)
			(size 0.4064 0.4064)
			(layers "F.Cu" "F.Mask" "F.Paste")
			(net "P1V8_AUX")
		)
		(pad "J9" smd circle
			(at -3.599942 -3.599942 180)
			(size 0.4064 0.4064)
			(layers "F.Cu" "F.Mask" "F.Paste")
			(net "P1V0_STBY_PLAVDD")
		)
		(pad "J10" smd circle
			(at -2.800096 -3.599942 180)
			(size 0.4064 0.4064)
			(layers "F.Cu" "F.Mask" "F.Paste")
			(net "P3V3_BMC_USB2AV33")
		)
		(pad "J11" smd circle
			(at -1.999996 -3.599942 180)
			(size 0.4064 0.4064)
			(layers "F.Cu" "F.Mask" "F.Paste")
			(net "GND")
		)
		(pad "J12" smd circle
			(at -1.199896 -3.599942 180)
			(size 0.4064 0.4064)
			(layers "F.Cu" "F.Mask" "F.Paste")
			(net "P1V8_AUX")
		)
		(pad "J13" smd circle
			(at -0.40005 -3.599942 180)
			(size 0.4064 0.4064)
			(layers "F.Cu" "F.Mask" "F.Paste")
			(net "GND")
		)
		(pad "J14" smd circle
			(at 0.40005 -3.599942 180)
			(size 0.4064 0.4064)
			(layers "F.Cu" "F.Mask" "F.Paste")
			(net "GND")
		)
		(pad "J15" smd circle
			(at 1.199896 -3.599942 180)
			(size 0.4064 0.4064)
			(layers "F.Cu" "F.Mask" "F.Paste")
			(net "GND")
		)
		(pad "J16" smd circle
			(at 1.999996 -3.599942 180)
			(size 0.4064 0.4064)
			(layers "F.Cu" "F.Mask" "F.Paste")
			(net "GND")
		)
		(pad "J17" smd circle
			(at 2.800096 -3.599942 180)
			(size 0.4064 0.4064)
			(layers "F.Cu" "F.Mask" "F.Paste")
			(net "GND")
		)
		(pad "J18" smd circle
			(at 3.599942 -3.599942 180)
			(size 0.4064 0.4064)
			(layers "F.Cu" "F.Mask" "F.Paste")
			(net "GND")
		)
		(pad "J19" smd circle
			(at 4.400042 -3.599942 180)
			(size 0.4064 0.4064)
			(layers "F.Cu" "F.Mask" "F.Paste")
			(net "GND")
		)
		(pad "J21" smd circle
			(at 5.999988 -3.599942 180)
			(size 0.4064 0.4064)
			(layers "F.Cu" "F.Mask" "F.Paste")
			(net "P3V3_P2V5_P1V8_RVDD")
		)
		(pad "J22" smd circle
			(at 6.800088 -3.599942 180)
			(size 0.4064 0.4064)
			(layers "F.Cu" "F.Mask" "F.Paste")
			(net "FM_CPU_RMCA_CATERR_LVT3_R_N")
		)
		(pad "J23" smd circle
			(at 7.599934 -3.599942 180)
			(size 0.4064 0.4064)
			(layers "F.Cu" "F.Mask" "F.Paste")
			(net "FM_BMC_MUX_CS_SPI_SEL_0")
		)
		(pad "J24" smd circle
			(at 8.400034 -3.599942 180)
			(size 0.4064 0.4064)
			(layers "F.Cu" "F.Mask" "F.Paste")
			(net "IRQ_BMC_CPU_NMI")
		)
		(pad "J25" smd circle
			(at 9.19988 -3.599942 180)
			(size 0.4064 0.4064)
			(layers "F.Cu" "F.Mask" "F.Paste")
			(net "SMB_BMC_ALERT4_R_N")
		)
		(pad "J26" smd circle
			(at 9.99998 -3.599942 180)
			(size 0.4064 0.4064)
			(layers "F.Cu" "F.Mask" "F.Paste")
			(net "FM_ME_BT_DONE")
		)
		(pad "K1" smd circle
			(at -9.99998 -2.800096 180)
			(size 0.4064 0.4064)
			(layers "F.Cu" "F.Mask" "F.Paste")
			(net "M_BMC_DDR4_MCLK_DN")
		)
		(pad "K2" smd circle
			(at -9.19988 -2.800096 180)
			(size 0.4064 0.4064)
			(layers "F.Cu" "F.Mask" "F.Paste")
			(net "M_BMC_DDR4_MCLK_DP")
		)
		(pad "K3" smd circle
			(at -8.400034 -2.800096 180)
			(size 0.4064 0.4064)
			(layers "F.Cu" "F.Mask" "F.Paste")
			(net "M_BMC_DDR4_MA<13>")
		)
		(pad "K4" smd circle
			(at -7.599934 -2.800096 180)
			(size 0.4064 0.4064)
			(layers "F.Cu" "F.Mask" "F.Paste")
			(net "GND")
		)
		(pad "K5" smd circle
			(at -6.800088 -2.800096 180)
			(size 0.4064 0.4064)
			(layers "F.Cu" "F.Mask" "F.Paste")
			(net "M_BMC_DDR4_MA<1>")
		)
		(pad "K6" smd circle
			(at -5.999988 -2.800096 180)
			(size 0.4064 0.4064)
			(layers "F.Cu" "F.Mask" "F.Paste")
			(net "P1V2_AUX")
		)
		(pad "K8" smd circle
			(at -4.400042 -2.800096 180)
			(size 0.4064 0.4064)
			(layers "F.Cu" "F.Mask" "F.Paste")
			(net "GND")
		)
		(pad "K9" smd circle
			(at -3.599942 -2.800096 180)
			(size 0.4064 0.4064)
			(layers "F.Cu" "F.Mask" "F.Paste")
			(net "GND")
		)
		(pad "K10" smd circle
			(at -2.800096 -2.800096 180)
			(size 0.4064 0.4064)
			(layers "F.Cu" "F.Mask" "F.Paste")
			(net "P1V8_BMC_USB2AV18")
		)
		(pad "K11" smd circle
			(at -1.999996 -2.800096 180)
			(size 0.4064 0.4064)
			(layers "F.Cu" "F.Mask" "F.Paste")
			(net "P3V3_RGM")
		)
		(pad "K12" smd circle
			(at -1.199896 -2.800096 180)
			(size 0.4064 0.4064)
			(layers "F.Cu" "F.Mask" "F.Paste")
			(net "P3V3_RGM")
		)
		(pad "K13" smd circle
			(at -0.40005 -2.800096 180)
			(size 0.4064 0.4064)
			(layers "F.Cu" "F.Mask" "F.Paste")
			(net "GND")
		)
		(pad "K14" smd circle
			(at 0.40005 -2.800096 180)
			(size 0.4064 0.4064)
			(layers "F.Cu" "F.Mask" "F.Paste")
			(net "GND")
		)
		(pad "K15" smd circle
			(at 1.199896 -2.800096 180)
			(size 0.4064 0.4064)
			(layers "F.Cu" "F.Mask" "F.Paste")
			(net "GND")
		)
		(pad "K16" smd circle
			(at 1.999996 -2.800096 180)
			(size 0.4064 0.4064)
			(layers "F.Cu" "F.Mask" "F.Paste")
			(net "P1V2_AUX")
		)
		(pad "K17" smd circle
			(at 2.800096 -2.800096 180)
			(size 0.4064 0.4064)
			(layers "F.Cu" "F.Mask" "F.Paste")
			(net "P1V2_AUX")
		)
		(pad "K18" smd circle
			(at 3.599942 -2.800096 180)
			(size 0.4064 0.4064)
			(layers "F.Cu" "F.Mask" "F.Paste")
			(net "P1V2_AUX")
		)
		(pad "K19" smd circle
			(at 4.400042 -2.800096 180)
			(size 0.4064 0.4064)
			(layers "F.Cu" "F.Mask" "F.Paste")
			(net "P1V2_AUX")
		)
		(pad "K21" smd circle
			(at 5.999988 -2.800096 180)
			(size 0.4064 0.4064)
			(layers "F.Cu" "F.Mask" "F.Paste")
			(net "P3V3_P2V5_P1V8_RVDD")
		)
		(pad "K22" smd circle
			(at 6.800088 -2.800096 180)
			(size 0.4064 0.4064)
			(layers "F.Cu" "F.Mask" "F.Paste")
			(net "GND")
		)
		(pad "K23" smd circle
			(at 7.599934 -2.800096 180)
			(size 0.4064 0.4064)
			(layers "F.Cu" "F.Mask" "F.Paste")
			(net "VOL_SEN_ALERT_R")
		)
		(pad "K24" smd circle
			(at 8.400034 -2.800096 180)
			(size 0.4064 0.4064)
			(layers "F.Cu" "F.Mask" "F.Paste")
			(net "SMB_BMC_MM12_R_SDA")
		)
		(pad "K25" smd circle
			(at 9.19988 -2.800096 180)
			(size 0.4064 0.4064)
			(layers "F.Cu" "F.Mask" "F.Paste")
			(net "SMB_BMC_MM14_R_SDA")
		)
		(pad "K26" smd circle
			(at 9.99998 -2.800096 180)
			(size 0.4064 0.4064)
			(layers "F.Cu" "F.Mask" "F.Paste")
			(net "SMB_BMC_MM13_R_SCL")
		)
		(pad "L1" smd circle
			(at -9.99998 -1.999996 180)
			(size 0.4064 0.4064)
			(layers "F.Cu" "F.Mask" "F.Paste")
			(net "M_BMC_DDR4_MA<5>")
		)
		(pad "L2" smd circle
			(at -9.19988 -1.999996 180)
			(size 0.4064 0.4064)
			(layers "F.Cu" "F.Mask" "F.Paste")
			(net "GND")
		)
		(pad "L3" smd circle
			(at -8.400034 -1.999996 180)
			(size 0.4064 0.4064)
			(layers "F.Cu" "F.Mask" "F.Paste")
			(net "M_BMC_DDR4_RST_N")
		)
		(pad "L4" smd circle
			(at -7.599934 -1.999996 180)
			(size 0.4064 0.4064)
			(layers "F.Cu" "F.Mask" "F.Paste")
			(net "M_BMC_DDR4_MA<12>")
		)
		(pad "L5" smd circle
			(at -6.800088 -1.999996 180)
			(size 0.4064 0.4064)
			(layers "F.Cu" "F.Mask" "F.Paste")
			(net "M_BMC_DDR4_MCKE")
		)
		(pad "L6" smd circle
			(at -5.999988 -1.999996 180)
			(size 0.4064 0.4064)
			(layers "F.Cu" "F.Mask" "F.Paste")
			(net "P1V2_AUX")
		)
		(pad "L8" smd circle
			(at -4.400042 -1.999996 180)
			(size 0.4064 0.4064)
			(layers "F.Cu" "F.Mask" "F.Paste")
			(net "GND")
		)
		(pad "L9" smd circle
			(at -3.599942 -1.999996 180)
			(size 0.4064 0.4064)
			(layers "F.Cu" "F.Mask" "F.Paste")
			(net "P1V0_AUX")
		)
		(pad "L10" smd circle
			(at -2.800096 -1.999996 180)
			(size 0.4064 0.4064)
			(layers "F.Cu" "F.Mask" "F.Paste")
			(net "P1V0_AUX")
		)
		(pad "L11" smd circle
			(at -1.999996 -1.999996 180)
			(size 0.4064 0.4064)
			(layers "F.Cu" "F.Mask" "F.Paste")
			(net "GND")
		)
		(pad "L12" smd circle
			(at -1.199896 -1.999996 180)
			(size 0.4064 0.4064)
			(layers "F.Cu" "F.Mask" "F.Paste")
			(net "GND")
		)
		(pad "L13" smd circle
			(at -0.40005 -1.999996 180)
			(size 0.4064 0.4064)
			(layers "F.Cu" "F.Mask" "F.Paste")
			(net "P1V8_AUX")
		)
		(pad "L14" smd circle
			(at 0.40005 -1.999996 180)
			(size 0.4064 0.4064)
			(layers "F.Cu" "F.Mask" "F.Paste")
			(net "P1V2_AUX")
		)
		(pad "L15" smd circle
			(at 1.199896 -1.999996 180)
			(size 0.4064 0.4064)
			(layers "F.Cu" "F.Mask" "F.Paste")
			(net "GND")
		)
		(pad "L16" smd circle
			(at 1.999996 -1.999996 180)
			(size 0.4064 0.4064)
			(layers "F.Cu" "F.Mask" "F.Paste")
			(net "GND")
		)
		(pad "L17" smd circle
			(at 2.800096 -1.999996 180)
			(size 0.4064 0.4064)
			(layers "F.Cu" "F.Mask" "F.Paste")
			(net "GND")
		)
		(pad "L18" smd circle
			(at 3.599942 -1.999996 180)
			(size 0.4064 0.4064)
			(layers "F.Cu" "F.Mask" "F.Paste")
			(net "GND")
		)
		(pad "L19" smd circle
			(at 4.400042 -1.999996 180)
			(size 0.4064 0.4064)
			(layers "F.Cu" "F.Mask" "F.Paste")
			(net "GND")
		)
		(pad "L21" smd circle
			(at 5.999988 -1.999996 180)
			(size 0.4064 0.4064)
			(layers "F.Cu" "F.Mask" "F.Paste")
			(net "P1V2_AUX")
		)
		(pad "L22" smd circle
			(at 6.800088 -1.999996 180)
			(size 0.4064 0.4064)
			(layers "F.Cu" "F.Mask" "F.Paste")
			(net "P3V3_P2V5_P1V8_RVDD")
		)
		(pad "L23" smd circle
			(at 7.599934 -1.999996 180)
			(size 0.4064 0.4064)
			(layers "F.Cu" "F.Mask" "F.Paste")
			(net "SMB_BMC_MM14_R_SCL")
		)
		(pad "L24" smd circle
			(at 8.400034 -1.999996 180)
			(size 0.4064 0.4064)
			(layers "F.Cu" "F.Mask" "F.Paste")
			(net "SMB_BMC_MM13_R_SDA")
		)
		(pad "L25" smd circle
			(at 9.19988 -1.999996 180)
			(size 0.4064 0.4064)
			(layers "F.Cu" "F.Mask" "F.Paste")
			(net "GND")
		)
		(pad "L26" smd circle
			(at 9.99998 -1.999996 180)
			(size 0.4064 0.4064)
			(layers "F.Cu" "F.Mask" "F.Paste")
			(net "SMB_BMC_MM12_R_SCL")
		)
		(pad "M1" smd circle
			(at -9.99998 -1.199896 180)
			(size 0.4064 0.4064)
			(layers "F.Cu" "F.Mask" "F.Paste")
			(net "M_BMC_DDR4_MA<8>")
		)
		(pad "M2" smd circle
			(at -9.19988 -1.199896 180)
			(size 0.4064 0.4064)
			(layers "F.Cu" "F.Mask" "F.Paste")
			(net "M_BMC_DDR4_MA<7>")
		)
		(pad "M3" smd circle
			(at -8.400034 -1.199896 180)
			(size 0.4064 0.4064)
			(layers "F.Cu" "F.Mask" "F.Paste")
			(net "M_BMC_DDR4_MBG1")
		)
		(pad "M4" smd circle
			(at -7.599934 -1.199896 180)
			(size 0.4064 0.4064)
			(layers "F.Cu" "F.Mask" "F.Paste")
			(net "GND")
		)
		(pad "M5" smd circle
			(at -6.800088 -1.199896 180)
			(size 0.4064 0.4064)
			(layers "F.Cu" "F.Mask" "F.Paste")
			(net "M_BMC_DDR4_MA<6>")
		)
		(pad "M6" smd circle
			(at -5.999988 -1.199896 180)
			(size 0.4064 0.4064)
			(layers "F.Cu" "F.Mask" "F.Paste")
			(net "P1V2_STBY_MVDD_CK")
		)
		(pad "M8" smd circle
			(at -4.400042 -1.199896 180)
			(size 0.4064 0.4064)
			(layers "F.Cu" "F.Mask" "F.Paste")
			(net "P1V0_AUX")
		)
		(pad "M9" smd circle
			(at -3.599942 -1.199896 180)
			(size 0.4064 0.4064)
			(layers "F.Cu" "F.Mask" "F.Paste")
			(net "GND")
		)
		(pad "M10" smd circle
			(at -2.800096 -1.199896 180)
			(size 0.4064 0.4064)
			(layers "F.Cu" "F.Mask" "F.Paste")
			(net "GND")
		)
		(pad "M11" smd circle
			(at -1.999996 -1.199896 180)
			(size 0.4064 0.4064)
			(layers "F.Cu" "F.Mask" "F.Paste")
			(net "P1V0_AUX")
		)
		(pad "M12" smd circle
			(at -1.199896 -1.199896 180)
			(size 0.4064 0.4064)
			(layers "F.Cu" "F.Mask" "F.Paste")
			(net "GND")
		)
		(pad "M13" smd circle
			(at -0.40005 -1.199896 180)
			(size 0.4064 0.4064)
			(layers "F.Cu" "F.Mask" "F.Paste")
			(net "P1V8_AUX")
		)
		(pad "M14" smd circle
			(at 0.40005 -1.199896 180)
			(size 0.4064 0.4064)
			(layers "F.Cu" "F.Mask" "F.Paste")
			(net "P1V2_AUX")
		)
		(pad "M15" smd circle
			(at 1.199896 -1.199896 180)
			(size 0.4064 0.4064)
			(layers "F.Cu" "F.Mask" "F.Paste")
			(net "GND")
		)
		(pad "M16" smd circle
			(at 1.999996 -1.199896 180)
			(size 0.4064 0.4064)
			(layers "F.Cu" "F.Mask" "F.Paste")
			(net "GND")
		)
		(pad "M17" smd circle
			(at 2.800096 -1.199896 180)
			(size 0.4064 0.4064)
			(layers "F.Cu" "F.Mask" "F.Paste")
			(net "GND")
		)
		(pad "M18" smd circle
			(at 3.599942 -1.199896 180)
			(size 0.4064 0.4064)
			(layers "F.Cu" "F.Mask" "F.Paste")
			(net "GND")
		)
		(pad "M19" smd circle
			(at 4.400042 -1.199896 180)
			(size 0.4064 0.4064)
			(layers "F.Cu" "F.Mask" "F.Paste")
			(net "GND")
		)
		(pad "M21" smd circle
			(at 5.999988 -1.199896 180)
			(size 0.4064 0.4064)
			(layers "F.Cu" "F.Mask" "F.Paste")
			(net "P1V2_AUX")
		)
		(pad "M22" smd circle
			(at 6.800088 -1.199896 180)
			(size 0.4064 0.4064)
			(layers "F.Cu" "F.Mask" "F.Paste")
			(net "P3V3_P2V5_P1V8_RVDD")
		)
		(pad "M23" smd circle
			(at 7.599934 -1.199896 180)
			(size 0.4064 0.4064)
			(layers "F.Cu" "F.Mask" "F.Paste")
			(net "LED_POSTCODE_5")
		)
		(pad "M24" smd circle
			(at 8.400034 -1.199896 180)
			(size 0.4064 0.4064)
			(layers "F.Cu" "F.Mask" "F.Paste")
			(net "FM_PFR_DSW_PWROK_N")
		)
		(pad "M25" smd circle
			(at 9.19988 -1.199896 180)
			(size 0.4064 0.4064)
			(layers "F.Cu" "F.Mask" "F.Paste")
			(net "RST_PFR_OVR_RTC_R")
		)
		(pad "M26" smd circle
			(at 9.99998 -1.199896 180)
			(size 0.4064 0.4064)
			(layers "F.Cu" "F.Mask" "F.Paste")
			(net "LED_POSTCODE_7")
		)
		(pad "N1" smd circle
			(at -9.99998 -0.40005 180)
			(size 0.4064 0.4064)
			(layers "F.Cu" "F.Mask" "F.Paste")
			(net "M_BMC_DDR4_MA<9>")
		)
		(pad "N2" smd circle
			(at -9.19988 -0.40005 180)
			(size 0.4064 0.4064)
			(layers "F.Cu" "F.Mask" "F.Paste")
			(net "GND")
		)
	)
)
